(kicad_pcb
	(version 20260206)
	(generator "pcbnew")
	(generator_version "10.0")
	(general
		(thickness 1.6)
		(legacy_teardrops no)
	)
	(paper "A4")
	(title_block
		(title "Bryce Canyon_IOM_M2_16342-2_OCP.brd")
		(comment 1 "Bryce Canyon / footprints 741-747 of 1146")
	)
	(layers
		(0 "F.Cu" signal "TOP")
		(4 "In1.Cu" signal "L2GND")
		(6 "In2.Cu" signal "L3")
		(8 "In3.Cu" signal "L4VCC")
		(10 "In4.Cu" signal "L5VCC")
		(12 "In5.Cu" signal "L6")
		(14 "In6.Cu" signal "L7GND")
		(2 "B.Cu" signal "BOTTOM")
		(9 "F.Adhes" user "F.Adhesive")
		(11 "B.Adhes" user "B.Adhesive")
		(13 "F.Paste" user "Package Geometry/Pastemask Top")
		(15 "B.Paste" user "Package Geometry/Pastemask Bottom")
		(5 "F.SilkS" user "Ref Des/Silkscreen Top")
		(7 "B.SilkS" user "Ref Des/Silkscreen Bottom")
		(1 "F.Mask" user "Board Geometry/Soldermask Top")
		(3 "B.Mask" user "Board Geometry/Soldermask Bottom")
		(17 "Dwgs.User" user "User.Drawings")
		(19 "Cmts.User" user "User.Comments")
		(21 "Eco1.User" user "User.Eco1")
		(23 "Eco2.User" user "User.Eco2")
		(25 "Edge.Cuts" user "Board Geometry/Outline")
		(27 "Margin" user)
		(31 "F.CrtYd" user "Package Geometry/Place Bound Top")
		(29 "B.CrtYd" user "Package Geometry/Place Bound Bottom")
		(35 "F.Fab" user "Ref Des/Assembly Top")
		(33 "B.Fab" user "Ref Des/Assembly Bottom")
	)
	(footprint ""
		(layer "B.Cu")
		(at 77.7494 -167.9702 90)
		(property "Reference" "R330"
			(at 0 0 90)
			(layer "B.SilkS")
			(hide yes)
			(effects
				(font
					(size 1.27 1.27)
				)
				(justify mirror)
			)
		)
		(property "Value" "4K7R2F-GP"
			(at -0.064008 -3.993896 90)
			(unlocked yes)
			(layer "B.Fab")
			(hide yes)
			(effects
				(font
					(size 1.016 1.016)
					(thickness 0.1524)
				)
				(justify mirror)
			)
		)
		(property "Device Type" "R402H16"
			(at -0.064008 -5.517896 90)
			(unlocked yes)
			(layer "B.Fab")
			(hide yes)
			(effects
				(font
					(size 1.016 1.016)
					(thickness 0.1524)
				)
				(justify mirror)
			)
		)
		(duplicate_pad_numbers_are_jumpers no)
		(fp_line
			(start 0.508 -0.9398)
			(end 0.508 0.9398)
			(stroke
				(width 0.1524)
				(type default)
			)
			(layer "B.SilkS")
		)
		(fp_line
			(start -0.508 -0.9398)
			(end 0.508 -0.9398)
			(stroke
				(width 0.1524)
				(type default)
			)
			(layer "B.SilkS")
		)
		(fp_rect
			(start 0.508 0.9398)
			(end -0.508 -0.9398)
			(stroke
				(width 0)
				(type default)
			)
			(fill no)
			(layer "B.CrtYd")
		)
		(fp_rect
			(start 0.508 0.9398)
			(end -0.508 -0.9398)
			(stroke
				(width 0)
				(type default)
			)
			(fill no)
			(layer "B.Fab")
		)
		(pad "1" smd custom
			(at 0 -0.4445 270)
			(size 0.1397 0.1397)
			(layers "B.Cu" "B.Mask" "B.Paste")
			(net "P3V3_STBY")
			(options
				(clearance outline)
				(anchor circle)
			)
			(primitives
				(gr_poly
					(pts
						(arc
							(start -0.1778 0.2794)
							(mid -0.249642 0.249642)
							(end -0.2794 0.1778)
						)
						(arc
							(start -0.2794 -0.1778)
							(mid -0.249642 -0.249642)
							(end -0.1778 -0.2794)
						)
						(arc
							(start 0.1778 -0.2794)
							(mid 0.249642 -0.249642)
							(end 0.2794 -0.1778)
						)
						(arc
							(start 0.2794 0.1778)
							(mid 0.249642 0.249642)
							(end 0.1778 0.2794)
						)
					)
					(width 0)
					(fill yes)
				)
			)
		)
		(pad "2" smd custom
			(at 0 0.4445 270)
			(size 0.1397 0.1397)
			(layers "B.Cu" "B.Mask" "B.Paste")
			(net "UART_EXP_BMC_TX")
			(options
				(clearance outline)
				(anchor circle)
			)
			(primitives
				(gr_poly
					(pts
						(arc
							(start -0.1778 0.2794)
							(mid -0.249642 0.249642)
							(end -0.2794 0.1778)
						)
						(arc
							(start -0.2794 -0.1778)
							(mid -0.249642 -0.249642)
							(end -0.1778 -0.2794)
						)
						(arc
							(start 0.1778 -0.2794)
							(mid 0.249642 -0.249642)
							(end 0.2794 -0.1778)
						)
						(arc
							(start 0.2794 0.1778)
							(mid 0.249642 0.249642)
							(end 0.1778 0.2794)
						)
					)
					(width 0)
					(fill yes)
				)
			)
		)
	)
	(footprint ""
		(layer "B.Cu")
		(at 59.2582 -138.5316)
		(property "Reference" "R273"
			(at 0 0 0)
			(layer "B.SilkS")
			(hide yes)
			(effects
				(font
					(size 1.27 1.27)
				)
				(justify mirror)
			)
		)
		(property "Value" "4K7R2F-GP"
			(at -0.064008 -3.993896 0)
			(unlocked yes)
			(layer "B.Fab")
			(hide yes)
			(effects
				(font
					(size 1.016 1.016)
					(thickness 0.1524)
				)
				(justify mirror)
			)
		)
		(property "Device Type" "R402H16"
			(at -0.064008 -5.517896 0)
			(unlocked yes)
			(layer "B.Fab")
			(hide yes)
			(effects
				(font
					(size 1.016 1.016)
					(thickness 0.1524)
				)
				(justify mirror)
			)
		)
		(duplicate_pad_numbers_are_jumpers no)
		(fp_line
			(start -0.508 -0.9398)
			(end 0.508 -0.9398)
			(stroke
				(width 0.1524)
				(type default)
			)
			(layer "B.SilkS")
		)
		(fp_line
			(start 0.508 -0.9398)
			(end 0.508 0.9398)
			(stroke
				(width 0.1524)
				(type default)
			)
			(layer "B.SilkS")
		)
		(fp_rect
			(start 0.508 0.9398)
			(end -0.508 -0.9398)
			(stroke
				(width 0)
				(type default)
			)
			(fill no)
			(layer "B.CrtYd")
		)
		(fp_rect
			(start 0.508 0.9398)
			(end -0.508 -0.9398)
			(stroke
				(width 0)
				(type default)
			)
			(fill no)
			(layer "B.Fab")
		)
		(pad "1" smd custom
			(at 0 -0.4445 180)
			(size 0.1397 0.1397)
			(layers "B.Cu" "B.Mask" "B.Paste")
			(net "SYS_PWR_LED")
			(options
				(clearance outline)
				(anchor circle)
			)
			(primitives
				(gr_poly
					(pts
						(arc
							(start -0.1778 0.2794)
							(mid -0.249642 0.249642)
							(end -0.2794 0.1778)
						)
						(arc
							(start -0.2794 -0.1778)
							(mid -0.249642 -0.249642)
							(end -0.1778 -0.2794)
						)
						(arc
							(start 0.1778 -0.2794)
							(mid 0.249642 -0.249642)
							(end 0.2794 -0.1778)
						)
						(arc
							(start 0.2794 0.1778)
							(mid 0.249642 0.249642)
							(end 0.1778 0.2794)
						)
					)
					(width 0)
					(fill yes)
				)
			)
		)
		(pad "2" smd custom
			(at 0 0.4445 180)
			(size 0.1397 0.1397)
			(layers "B.Cu" "B.Mask" "B.Paste")
			(net "GND")
			(options
				(clearance outline)
				(anchor circle)
			)
			(primitives
				(gr_poly
					(pts
						(arc
							(start -0.1778 0.2794)
							(mid -0.249642 0.249642)
							(end -0.2794 0.1778)
						)
						(arc
							(start -0.2794 -0.1778)
							(mid -0.249642 -0.249642)
							(end -0.1778 -0.2794)
						)
						(arc
							(start 0.1778 -0.2794)
							(mid 0.249642 -0.249642)
							(end 0.2794 -0.1778)
						)
						(arc
							(start 0.2794 0.1778)
							(mid 0.249642 0.249642)
							(end 0.1778 0.2794)
						)
					)
					(width 0)
					(fill yes)
				)
			)
		)
	)
	(footprint ""
		(layer "B.Cu")
		(at 57.58815 -122.974354 90)
		(property "Reference" "R345"
			(at 0 0 90)
			(layer "B.SilkS")
			(hide yes)
			(effects
				(font
					(size 1.27 1.27)
				)
				(justify mirror)
			)
		)
		(property "Value" "0R2J-2-GP"
			(at -0.064008 -3.993896 90)
			(unlocked yes)
			(layer "B.Fab")
			(hide yes)
			(effects
				(font
					(size 1.016 1.016)
					(thickness 0.1524)
				)
				(justify mirror)
			)
		)
		(property "Device Type" "R402H16"
			(at -0.064008 -5.517896 90)
			(unlocked yes)
			(layer "B.Fab")
			(hide yes)
			(effects
				(font
					(size 1.016 1.016)
					(thickness 0.1524)
				)
				(justify mirror)
			)
		)
		(duplicate_pad_numbers_are_jumpers no)
		(fp_line
			(start 0.508 -0.9398)
			(end 0.508 0.9398)
			(stroke
				(width 0.1524)
				(type default)
			)
			(layer "B.SilkS")
		)
		(fp_line
			(start -0.508 -0.9398)
			(end 0.508 -0.9398)
			(stroke
				(width 0.1524)
				(type default)
			)
			(layer "B.SilkS")
		)
		(fp_rect
			(start 0.508 0.9398)
			(end -0.508 -0.9398)
			(stroke
				(width 0)
				(type default)
			)
			(fill no)
			(layer "B.CrtYd")
		)
		(fp_rect
			(start 0.508 0.9398)
			(end -0.508 -0.9398)
			(stroke
				(width 0)
				(type default)
			)
			(fill no)
			(layer "B.Fab")
		)
		(pad "1" smd custom
			(at 0 -0.4445 270)
			(size 0.1397 0.1397)
			(layers "B.Cu" "B.Mask" "B.Paste")
			(net "DEBUG_RST_BTN_N_R")
			(options
				(clearance outline)
				(anchor circle)
			)
			(primitives
				(gr_poly
					(pts
						(arc
							(start -0.1778 0.2794)
							(mid -0.249642 0.249642)
							(end -0.2794 0.1778)
						)
						(arc
							(start -0.2794 -0.1778)
							(mid -0.249642 -0.249642)
							(end -0.1778 -0.2794)
						)
						(arc
							(start 0.1778 -0.2794)
							(mid 0.249642 -0.249642)
							(end 0.2794 -0.1778)
						)
						(arc
							(start 0.2794 0.1778)
							(mid 0.249642 0.249642)
							(end 0.1778 0.2794)
						)
					)
					(width 0)
					(fill yes)
				)
			)
		)
		(pad "2" smd custom
			(at 0 0.4445 270)
			(size 0.1397 0.1397)
			(layers "B.Cu" "B.Mask" "B.Paste")
			(net "DEBUG_RST_BTN_N")
			(options
				(clearance outline)
				(anchor circle)
			)
			(primitives
				(gr_poly
					(pts
						(arc
							(start -0.1778 0.2794)
							(mid -0.249642 0.249642)
							(end -0.2794 0.1778)
						)
						(arc
							(start -0.2794 -0.1778)
							(mid -0.249642 -0.249642)
							(end -0.1778 -0.2794)
						)
						(arc
							(start 0.1778 -0.2794)
							(mid 0.249642 -0.249642)
							(end 0.2794 -0.1778)
						)
						(arc
							(start 0.2794 0.1778)
							(mid 0.249642 0.249642)
							(end 0.1778 0.2794)
						)
					)
					(width 0)
					(fill yes)
				)
			)
		)
	)
	(footprint ""
		(layer "B.Cu")
		(at 47.371 -124.206 -90)
		(property "Reference" "R156"
			(at 0 0 90)
			(layer "B.SilkS")
			(hide yes)
			(effects
				(font
					(size 1.27 1.27)
				)
				(justify mirror)
			)
		)
		(property "Value" "0R2J-2-GP"
			(at -0.064008 -3.993896 270)
			(unlocked yes)
			(layer "B.Fab")
			(hide yes)
			(effects
				(font
					(size 1.016 1.016)
					(thickness 0.1524)
				)
				(justify mirror)
			)
		)
		(property "Device Type" "R402H16"
			(at -0.064008 -5.517896 270)
			(unlocked yes)
			(layer "B.Fab")
			(hide yes)
			(effects
				(font
					(size 1.016 1.016)
					(thickness 0.1524)
				)
				(justify mirror)
			)
		)
		(duplicate_pad_numbers_are_jumpers no)
		(fp_line
			(start -0.508 -0.9398)
			(end 0.508 -0.9398)
			(stroke
				(width 0.1524)
				(type default)
			)
			(layer "B.SilkS")
		)
		(fp_line
			(start 0.508 -0.9398)
			(end 0.508 0.9398)
			(stroke
				(width 0.1524)
				(type default)
			)
			(layer "B.SilkS")
		)
		(fp_rect
			(start 0.508 0.9398)
			(end -0.508 -0.9398)
			(stroke
				(width 0)
				(type default)
			)
			(fill no)
			(layer "B.CrtYd")
		)
		(fp_rect
			(start 0.508 0.9398)
			(end -0.508 -0.9398)
			(stroke
				(width 0)
				(type default)
			)
			(fill no)
			(layer "B.Fab")
		)
		(pad "1" smd custom
			(at 0 -0.4445 90)
			(size 0.1397 0.1397)
			(layers "B.Cu" "B.Mask" "B.Paste")
			(net "BMC_SMB2_CLK_TP")
			(options
				(clearance outline)
				(anchor circle)
			)
			(primitives
				(gr_poly
					(pts
						(arc
							(start -0.1778 0.2794)
							(mid -0.249642 0.249642)
							(end -0.2794 0.1778)
						)
						(arc
							(start -0.2794 -0.1778)
							(mid -0.249642 -0.249642)
							(end -0.1778 -0.2794)
						)
						(arc
							(start 0.1778 -0.2794)
							(mid 0.249642 -0.249642)
							(end 0.2794 -0.1778)
						)
						(arc
							(start 0.2794 0.1778)
							(mid 0.249642 0.249642)
							(end 0.1778 0.2794)
						)
					)
					(width 0)
					(fill yes)
				)
			)
		)
		(pad "2" smd custom
			(at 0 0.4445 90)
			(size 0.1397 0.1397)
			(layers "B.Cu" "B.Mask" "B.Paste")
			(net "BMC_SMB2_CLK")
			(options
				(clearance outline)
				(anchor circle)
			)
			(primitives
				(gr_poly
					(pts
						(arc
							(start -0.1778 0.2794)
							(mid -0.249642 0.249642)
							(end -0.2794 0.1778)
						)
						(arc
							(start -0.2794 -0.1778)
							(mid -0.249642 -0.249642)
							(end -0.1778 -0.2794)
						)
						(arc
							(start 0.1778 -0.2794)
							(mid 0.249642 -0.249642)
							(end 0.2794 -0.1778)
						)
						(arc
							(start 0.2794 0.1778)
							(mid 0.249642 0.249642)
							(end 0.1778 0.2794)
						)
					)
					(width 0)
					(fill yes)
				)
			)
		)
	)
	(footprint ""
		(layer "B.Cu")
		(at 65.4304 -138.0236)
		(property "Reference" "TP13"
			(at 0 0 0)
			(layer "B.SilkS")
			(hide yes)
			(effects
				(font
					(size 1.27 1.27)
				)
				(justify mirror)
			)
		)
		(property "Value" "TPAD28-2-GP"
			(at 0.0127 -1.6637 0)
			(unlocked yes)
			(layer "B.Fab")
			(hide yes)
			(effects
				(font
					(size 1.016 1.016)
					(thickness 0.1524)
				)
				(justify mirror)
			)
		)
		(property "Device Type" "TPAD28"
			(at 0.0127 -3.1877 0)
			(unlocked yes)
			(layer "B.Fab")
			(hide yes)
			(effects
				(font
					(size 1.016 1.016)
					(thickness 0.1524)
				)
				(justify mirror)
			)
		)
		(duplicate_pad_numbers_are_jumpers no)
		(fp_poly
			(pts
				(arc
					(start 0.3556 0)
					(mid -0.3556 0)
					(end 0.3556 0)
				)
			)
			(stroke
				(width 0)
				(type default)
			)
			(fill no)
			(layer "B.CrtYd")
		)
		(fp_poly
			(pts
				(arc
					(start 0.6096 0)
					(mid -0.6096 0)
					(end 0.6096 0)
				)
			)
			(stroke
				(width 0)
				(type default)
			)
			(fill no)
			(layer "B.Fab")
		)
		(pad "1" smd circle
			(at 0 0 180)
			(size 0.7112 0.7112)
			(layers "B.Cu" "B.Mask" "B.Paste")
			(net "TP_BMC_GPIOA0")
		)
	)
	(footprint ""
		(layer "B.Cu")
		(at 32.7914 -152.2222 180)
		(property "Reference" "C92"
			(at 0 0 0)
			(layer "B.SilkS")
			(hide yes)
			(effects
				(font
					(size 1.27 1.27)
				)
				(justify mirror)
			)
		)
		(property "Value" "SC1U16V3KX-5GP"
			(at 0 -2.8194 180)
			(unlocked yes)
			(layer "B.Fab")
			(hide yes)
			(effects
				(font
					(size 1.016 1.016)
					(thickness 0.1524)
				)
				(justify mirror)
			)
		)
		(property "Device Type" "C603H36"
			(at 0 -4.3434 180)
			(unlocked yes)
			(layer "B.Fab")
			(hide yes)
			(effects
				(font
					(size 1.016 1.016)
					(thickness 0.1524)
				)
				(justify mirror)
			)
		)
		(duplicate_pad_numbers_are_jumpers no)
		(fp_line
			(start -0.508 0)
			(end 0.508 0)
			(stroke
				(width 0.2032)
				(type default)
			)
			(layer "B.SilkS")
		)
		(fp_rect
			(start 0.5842 1.3335)
			(end -0.5842 -1.3335)
			(stroke
				(width 0)
				(type default)
			)
			(fill no)
			(layer "B.CrtYd")
		)
		(fp_rect
			(start 0.5842 1.3335)
			(end -0.5842 -1.3335)
			(stroke
				(width 0)
				(type default)
			)
			(fill no)
			(layer "B.Fab")
		)
		(pad "1" smd custom
			(at 0 -0.762)
			(size 0.2159 0.2159)
			(layers "B.Cu" "B.Mask" "B.Paste")
			(net "MPLLAV33")
			(options
				(clearance outline)
				(anchor circle)
			)
			(primitives
				(gr_poly
					(pts
						(arc
							(start -0.3302 0.4318)
							(mid -0.402042 0.402042)
							(end -0.4318 0.3302)
						)
						(arc
							(start -0.4318 -0.3302)
							(mid -0.402042 -0.402042)
							(end -0.3302 -0.4318)
						)
						(arc
							(start 0.3302 -0.4318)
							(mid 0.402042 -0.402042)
							(end 0.4318 -0.3302)
						)
						(arc
							(start 0.4318 0.3302)
							(mid 0.402042 0.402042)
							(end 0.3302 0.4318)
						)
					)
					(width 0)
					(fill yes)
				)
			)
		)
		(pad "2" smd custom
			(at 0 0.762)
			(size 0.2159 0.2159)
			(layers "B.Cu" "B.Mask" "B.Paste")
			(net "GND")
			(options
				(clearance outline)
				(anchor circle)
			)
			(primitives
				(gr_poly
					(pts
						(arc
							(start -0.3302 0.4318)
							(mid -0.402042 0.402042)
							(end -0.4318 0.3302)
						)
						(arc
							(start -0.4318 -0.3302)
							(mid -0.402042 -0.402042)
							(end -0.3302 -0.4318)
						)
						(arc
							(start 0.3302 -0.4318)
							(mid 0.402042 -0.402042)
							(end 0.4318 -0.3302)
						)
						(arc
							(start 0.4318 0.3302)
							(mid 0.402042 0.402042)
							(end 0.3302 0.4318)
						)
					)
					(width 0)
					(fill yes)
				)
			)
		)
	)
	(footprint ""
		(layer "B.Cu")
		(at 48.7172 -120.0912 -90)
		(property "Reference" "U27"
			(at 0 0 90)
			(layer "B.SilkS")
			(hide yes)
			(effects
				(font
					(size 1.27 1.27)
				)
				(justify mirror)
			)
		)
		(property "Value" "TMP75AIDGKR-GP"
			(at 0.1143 -9.1948 270)
			(unlocked yes)
			(layer "B.Fab")
			(hide yes)
			(effects
				(font
					(size 1.016 1.016)
					(thickness 0.1524)
				)
				(justify mirror)
			)
		)
		(property "Device Type" "MSOP8-1H44"
			(at 0.1143 -10.795 270)
			(unlocked yes)
			(layer "B.Fab")
			(hide yes)
			(effects
				(font
					(size 1.016 1.016)
					(thickness 0.1524)
				)
				(justify mirror)
			)
		)
		(duplicate_pad_numbers_are_jumpers no)
		(fp_line
			(start 1.778 1.0922)
			(end 1.778 3.048)
			(stroke
				(width 0.508)
				(type default)
			)
			(layer "B.SilkS")
		)
		(fp_line
			(start -1.0795 1.016)
			(end -1.0795 -1.016)
			(stroke
				(width 0.1524)
				(type default)
			)
			(layer "B.SilkS")
		)
		(fp_line
			(start 1.9558 1.016)
			(end -1.0795 1.016)
			(stroke
				(width 0.1524)
				(type default)
			)
			(layer "B.SilkS")
		)
		(fp_line
			(start 1.4478 -0.0381)
			(end 1.9558 0.4699)
			(stroke
				(width 0.1524)
				(type default)
			)
			(layer "B.SilkS")
		)
		(fp_line
			(start 1.9558 -0.5461)
			(end 1.4478 -0.0381)
			(stroke
				(width 0.1524)
				(type default)
			)
			(layer "B.SilkS")
		)
		(fp_line
			(start -1.0795 -1.016)
			(end 1.9558 -1.016)
			(stroke
				(width 0.1524)
				(type default)
			)
			(layer "B.SilkS")
		)
		(fp_line
			(start 1.9558 -1.016)
			(end 1.9558 1.016)
			(stroke
				(width 0.1524)
				(type default)
			)
			(layer "B.SilkS")
		)
		(fp_poly
			(pts
				(xy 1.1557 -1.016) (xy 1.1557 1.016) (xy -1.1557 1.016) (xy -1.1557 -1.016)
			)
			(stroke
				(width 0)
				(type default)
			)
			(fill yes)
			(layer "B.SilkS")
		)
		(fp_rect
			(start 1.4986 2.4511)
			(end -1.4986 -2.4511)
			(stroke
				(width 0)
				(type default)
			)
			(fill no)
			(layer "B.CrtYd")
		)
		(fp_poly
			(pts
				(xy 2.032 3.302) (xy 2.032 -3.302) (xy -2.032 -3.302) (xy -2.032 -2.1209) (xy -1.4986 -2.1209) (xy -1.4986 -2.4511)
				(xy 1.4986 -2.4511) (xy 1.4986 2.4511) (xy -1.4986 2.4511) (xy -1.4986 -2.1082) (xy -2.032 -2.1082)
				(xy -2.032 3.302)
			)
			(stroke
				(width 0)
				(type default)
			)
			(fill no)
			(layer "B.CrtYd")
		)
		(fp_rect
			(start 2.032 3.302)
			(end -2.032 -3.302)
			(stroke
				(width 0)
				(type default)
			)
			(fill no)
			(layer "B.Fab")
		)
		(pad "1" smd rect
			(at 0.97536 2.05486 90)
			(size 0.3556 1.524)
			(layers "B.Cu" "B.Mask" "B.Paste")
			(net "TEMP_3_SDA")
		)
		(pad "2" smd rect
			(at 0.32512 2.05486 90)
			(size 0.3556 1.524)
			(layers "B.Cu" "B.Mask" "B.Paste")
			(net "TEMP_3_SCL")
		)
		(pad "3" smd rect
			(at -0.32512 2.05486 90)
			(size 0.3556 1.524)
			(layers "B.Cu" "B.Mask" "B.Paste")
			(net "TEMP_3_ALERT")
		)
		(pad "4" smd rect
			(at -0.97536 2.05486 90)
			(size 0.3556 1.524)
			(layers "B.Cu" "B.Mask" "B.Paste")
			(net "GND")
		)
		(pad "5" smd rect
			(at -0.97536 -2.05486 90)
			(size 0.3556 1.524)
			(layers "B.Cu" "B.Mask" "B.Paste")
			(net "TEMP_3_A2")
		)
		(pad "6" smd rect
			(at -0.32512 -2.05486 90)
			(size 0.3556 1.524)
			(layers "B.Cu" "B.Mask" "B.Paste")
			(net "TEMP_3_A1")
		)
		(pad "7" smd rect
			(at 0.32512 -2.05486 90)
			(size 0.3556 1.524)
			(layers "B.Cu" "B.Mask" "B.Paste")
			(net "TEMP_3_A0")
		)
		(pad "8" smd rect
			(at 0.97536 -2.05486 90)
			(size 0.3556 1.524)
			(layers "B.Cu" "B.Mask" "B.Paste")
			(net "P3V3_STBY")
		)
	)
)
